(kicad_pcb
	(version 20260206)
	(generator "pcbnew")
	(generator_version "10.0")
	(general
		(thickness 1.6)
		(legacy_teardrops no)
	)
	(paper "A4")
	(title_block
		(title "04192023_DAF0TMB3IC0_F0TG_MB_C_brd_V02_OCP.brd")
		(comment 1 "Grand Teton / footprints 7138-7144 of 8354")
	)
	(layers
		(0 "F.Cu" signal "TOP")
		(4 "In1.Cu" signal "GND")
		(6 "In2.Cu" signal "IN1")
		(8 "In3.Cu" signal "GND1")
		(10 "In4.Cu" signal "IN2")
		(12 "In5.Cu" signal "GND2")
		(14 "In6.Cu" signal "IN3")
		(16 "In7.Cu" signal "GND3")
		(18 "In8.Cu" signal "VCC")
		(20 "In9.Cu" signal "VCC1")
		(22 "In10.Cu" signal "GND4")
		(24 "In11.Cu" signal "IN4")
		(26 "In12.Cu" signal "GND5")
		(28 "In13.Cu" signal "IN5")
		(30 "In14.Cu" signal "GND6")
		(32 "In15.Cu" signal "IN6")
		(34 "In16.Cu" signal "GND7")
		(2 "B.Cu" signal "BOTTOM")
		(9 "F.Adhes" user "F.Adhesive")
		(11 "B.Adhes" user "B.Adhesive")
		(13 "F.Paste" user "Package Geometry/Pastemask Top")
		(15 "B.Paste" user "Package Geometry/Pastemask Bottom")
		(5 "F.SilkS" user "Ref Des/Silkscreen Top")
		(7 "B.SilkS" user "Ref Des/Silkscreen Bottom")
		(1 "F.Mask" user "Board Geometry/Soldermask Top")
		(3 "B.Mask" user "Board Geometry/Soldermask Bottom")
		(17 "Dwgs.User" user "User.Drawings")
		(19 "Cmts.User" user "User.Comments")
		(21 "Eco1.User" user "User.Eco1")
		(23 "Eco2.User" user "User.Eco2")
		(25 "Edge.Cuts" user "Board Geometry/Outline")
		(27 "Margin" user)
		(31 "F.CrtYd" user "Package Geometry/Place Bound Top")
		(29 "B.CrtYd" user "Package Geometry/Place Bound Bottom")
		(35 "F.Fab" user "Ref Des/Assembly Top")
		(33 "B.Fab" user "Ref Des/Assembly Bottom")
	)
	(footprint ""
		(layer "B.Cu")
		(at 136.016238 -387.084062 -90)
		(property "Reference" "C433"
			(at 0 0 90)
			(layer "B.SilkS")
			(hide yes)
			(effects
				(font
					(size 1.27 1.27)
				)
				(justify mirror)
			)
		)
		(property "Value" ""
			(at 0 0 90)
			(layer "B.Fab")
			(effects
				(font
					(size 1.27 1.27)
				)
				(justify mirror)
			)
		)
		(duplicate_pad_numbers_are_jumpers no)
		(fp_line
			(start -1.524 0.762)
			(end 1.524 0.762)
			(stroke
				(width 0.1524)
				(type default)
			)
			(layer "B.SilkS")
		)
		(fp_line
			(start 1.524 0.762)
			(end 1.524 -0.762)
			(stroke
				(width 0.1524)
				(type default)
			)
			(layer "B.SilkS")
		)
		(fp_line
			(start -1.524 -0.762)
			(end -1.524 0.762)
			(stroke
				(width 0.1524)
				(type default)
			)
			(layer "B.SilkS")
		)
		(fp_line
			(start 1.524 -0.762)
			(end -1.524 -0.762)
			(stroke
				(width 0.1524)
				(type default)
			)
			(layer "B.SilkS")
		)
		(fp_line
			(start -1.1049 0.724916)
			(end -1.1049 -0.724916)
			(stroke
				(width 0.1)
				(type default)
			)
			(layer "B.Fab")
		)
		(fp_line
			(start 1.1049 0.724916)
			(end -1.1049 0.724916)
			(stroke
				(width 0.1)
				(type default)
			)
			(layer "B.Fab")
		)
		(fp_line
			(start -1.1049 -0.724916)
			(end 1.1049 -0.724916)
			(stroke
				(width 0.1)
				(type default)
			)
			(layer "B.Fab")
		)
		(fp_line
			(start 1.1049 -0.724916)
			(end 1.1049 0.724916)
			(stroke
				(width 0.1)
				(type default)
			)
			(layer "B.Fab")
		)
		(pad "1" smd rect
			(at 0.889 0 270)
			(size 1.016 1.27)
			(layers "B.Cu" "B.Mask" "B.Paste")
			(net "P1V8_CPU1_RT3_1A")
		)
		(pad "2" smd rect
			(at -0.889 0 270)
			(size 1.016 1.27)
			(layers "B.Cu" "B.Mask" "B.Paste")
			(net "GND")
		)
	)
	(footprint ""
		(layer "B.Cu")
		(at 166.955216 -112.902238 180)
		(property "Reference" "R9"
			(at 0 0 0)
			(layer "B.SilkS")
			(hide yes)
			(effects
				(font
					(size 1.27 1.27)
				)
				(justify mirror)
			)
		)
		(property "Value" ""
			(at 0 0 0)
			(layer "B.Fab")
			(effects
				(font
					(size 1.27 1.27)
				)
				(justify mirror)
			)
		)
		(duplicate_pad_numbers_are_jumpers no)
		(fp_line
			(start 0.7874 0.4064)
			(end 0.7874 -0.4064)
			(stroke
				(width 0.1524)
				(type default)
			)
			(layer "B.SilkS")
		)
		(fp_line
			(start 0.7874 -0.4064)
			(end -0.7874 -0.4064)
			(stroke
				(width 0.1524)
				(type default)
			)
			(layer "B.SilkS")
		)
		(fp_line
			(start -0.7874 0.4064)
			(end 0.7874 0.4064)
			(stroke
				(width 0.1524)
				(type default)
			)
			(layer "B.SilkS")
		)
		(fp_line
			(start -0.7874 -0.4064)
			(end -0.7874 0.4064)
			(stroke
				(width 0.1524)
				(type default)
			)
			(layer "B.SilkS")
		)
		(fp_line
			(start 0.67945 0.3048)
			(end 0.67945 -0.305054)
			(stroke
				(width 0.1)
				(type default)
			)
			(layer "B.Fab")
		)
		(fp_line
			(start 0.67945 -0.305054)
			(end 0.12065 -0.305054)
			(stroke
				(width 0.1)
				(type default)
			)
			(layer "B.Fab")
		)
		(fp_line
			(start 0.12065 0.3048)
			(end 0.67945 0.3048)
			(stroke
				(width 0.1)
				(type default)
			)
			(layer "B.Fab")
		)
		(fp_line
			(start 0.12065 0.2794)
			(end 0.12065 0.3048)
			(stroke
				(width 0.1)
				(type default)
			)
			(layer "B.Fab")
		)
		(fp_line
			(start 0.12065 -0.2794)
			(end -0.12065 -0.2794)
			(stroke
				(width 0.1)
				(type default)
			)
			(layer "B.Fab")
		)
		(fp_line
			(start 0.12065 -0.305054)
			(end 0.12065 -0.2794)
			(stroke
				(width 0.1)
				(type default)
			)
			(layer "B.Fab")
		)
		(fp_line
			(start -0.120396 0.3048)
			(end -0.120396 0.2794)
			(stroke
				(width 0.1)
				(type default)
			)
			(layer "B.Fab")
		)
		(fp_line
			(start -0.120396 0.2794)
			(end 0.12065 0.2794)
			(stroke
				(width 0.1)
				(type default)
			)
			(layer "B.Fab")
		)
		(fp_line
			(start -0.12065 -0.2794)
			(end -0.12065 -0.3048)
			(stroke
				(width 0.1)
				(type default)
			)
			(layer "B.Fab")
		)
		(fp_line
			(start -0.12065 -0.3048)
			(end -0.67945 -0.3048)
			(stroke
				(width 0.1)
				(type default)
			)
			(layer "B.Fab")
		)
		(fp_line
			(start -0.67945 0.3048)
			(end -0.120396 0.3048)
			(stroke
				(width 0.1)
				(type default)
			)
			(layer "B.Fab")
		)
		(fp_line
			(start -0.67945 -0.3048)
			(end -0.67945 0.3048)
			(stroke
				(width 0.1)
				(type default)
			)
			(layer "B.Fab")
		)
		(pad "1" smd circle
			(at 0.40005 0)
			(size 0 0)
			(layers "B.Cu" "B.Mask" "B.Paste")
			(net "JTAG_PLD_TDI")
		)
		(pad "2" smd circle
			(at -0.40005 0)
			(size 0 0)
			(layers "B.Cu" "B.Mask" "B.Paste")
			(net "JTAG_SCM_PLD_TDI")
		)
	)
	(footprint ""
		(layer "B.Cu")
		(at 218.059 -337.312 180)
		(property "Reference" "R6737"
			(at 0 0 0)
			(layer "B.SilkS")
			(hide yes)
			(effects
				(font
					(size 1.27 1.27)
				)
				(justify mirror)
			)
		)
		(property "Value" ""
			(at 0 0 0)
			(layer "B.Fab")
			(effects
				(font
					(size 1.27 1.27)
				)
				(justify mirror)
			)
		)
		(duplicate_pad_numbers_are_jumpers no)
		(fp_line
			(start 0.32512 0.175006)
			(end 0.32512 -0.175006)
			(stroke
				(width 0.1)
				(type default)
			)
			(layer "B.Fab")
		)
		(fp_line
			(start 0.32512 -0.175006)
			(end -0.32512 -0.175006)
			(stroke
				(width 0.1)
				(type default)
			)
			(layer "B.Fab")
		)
		(fp_line
			(start -0.32512 0.175006)
			(end 0.32512 0.175006)
			(stroke
				(width 0.1)
				(type default)
			)
			(layer "B.Fab")
		)
		(fp_line
			(start -0.32512 -0.175006)
			(end -0.32512 0.175006)
			(stroke
				(width 0.1)
				(type default)
			)
			(layer "B.Fab")
		)
		(pad "1" smd rect
			(at 0.2667 0)
			(size 0.3048 0.381)
			(layers "B.Cu" "B.Mask" "B.Paste")
			(net "SMB_RT_CPU1_P1_R_SCL")
		)
		(pad "2" smd rect
			(at -0.2667 0 180)
			(size 0.3048 0.381)
			(layers "B.Cu" "B.Mask" "B.Paste")
			(net "SMB_RT_CPU1_P1_SCL")
		)
	)
	(footprint ""
		(layer "B.Cu")
		(at 348.56547 -331.274928 -90)
		(property "Reference" "PC120_6"
			(at 0 0 90)
			(layer "B.SilkS")
			(hide yes)
			(effects
				(font
					(size 1.27 1.27)
				)
				(justify mirror)
			)
		)
		(property "Value" ""
			(at 0 0 90)
			(layer "B.Fab")
			(effects
				(font
					(size 1.27 1.27)
				)
				(justify mirror)
			)
		)
		(duplicate_pad_numbers_are_jumpers no)
		(fp_line
			(start -1.524 0.762)
			(end 1.524 0.762)
			(stroke
				(width 0.1524)
				(type default)
			)
			(layer "B.SilkS")
		)
		(fp_line
			(start 1.524 0.762)
			(end 1.524 -0.762)
			(stroke
				(width 0.1524)
				(type default)
			)
			(layer "B.SilkS")
		)
		(fp_line
			(start -1.524 -0.762)
			(end -1.524 0.762)
			(stroke
				(width 0.1524)
				(type default)
			)
			(layer "B.SilkS")
		)
		(fp_line
			(start 1.524 -0.762)
			(end -1.524 -0.762)
			(stroke
				(width 0.1524)
				(type default)
			)
			(layer "B.SilkS")
		)
		(fp_line
			(start -1.1049 0.724916)
			(end -1.1049 -0.724916)
			(stroke
				(width 0.1)
				(type default)
			)
			(layer "B.Fab")
		)
		(fp_line
			(start 1.1049 0.724916)
			(end -1.1049 0.724916)
			(stroke
				(width 0.1)
				(type default)
			)
			(layer "B.Fab")
		)
		(fp_line
			(start -1.1049 -0.724916)
			(end 1.1049 -0.724916)
			(stroke
				(width 0.1)
				(type default)
			)
			(layer "B.Fab")
		)
		(fp_line
			(start 1.1049 -0.724916)
			(end 1.1049 0.724916)
			(stroke
				(width 0.1)
				(type default)
			)
			(layer "B.Fab")
		)
		(pad "1" smd rect
			(at 0.889 0 270)
			(size 1.016 1.27)
			(layers "B.Cu" "B.Mask" "B.Paste")
			(net "PVDDCR_CPU1_P0")
		)
		(pad "2" smd rect
			(at -0.889 0 270)
			(size 1.016 1.27)
			(layers "B.Cu" "B.Mask" "B.Paste")
			(net "GND")
		)
	)
	(footprint ""
		(layer "B.Cu")
		(at 266.30376 -194.88531 180)
		(property "Reference" "R764"
			(at 0 0 0)
			(layer "B.SilkS")
			(hide yes)
			(effects
				(font
					(size 1.27 1.27)
				)
				(justify mirror)
			)
		)
		(property "Value" ""
			(at 0 0 0)
			(layer "B.Fab")
			(effects
				(font
					(size 1.27 1.27)
				)
				(justify mirror)
			)
		)
		(duplicate_pad_numbers_are_jumpers no)
		(fp_line
			(start 0.7874 0.4064)
			(end 0.7874 -0.4064)
			(stroke
				(width 0.1524)
				(type default)
			)
			(layer "B.SilkS")
		)
		(fp_line
			(start 0.7874 -0.4064)
			(end -0.7874 -0.4064)
			(stroke
				(width 0.1524)
				(type default)
			)
			(layer "B.SilkS")
		)
		(fp_line
			(start -0.7874 0.4064)
			(end 0.7874 0.4064)
			(stroke
				(width 0.1524)
				(type default)
			)
			(layer "B.SilkS")
		)
		(fp_line
			(start -0.7874 -0.4064)
			(end -0.7874 0.4064)
			(stroke
				(width 0.1524)
				(type default)
			)
			(layer "B.SilkS")
		)
		(fp_line
			(start 0.67945 0.3048)
			(end 0.67945 -0.305054)
			(stroke
				(width 0.1)
				(type default)
			)
			(layer "B.Fab")
		)
		(fp_line
			(start 0.67945 -0.305054)
			(end 0.12065 -0.305054)
			(stroke
				(width 0.1)
				(type default)
			)
			(layer "B.Fab")
		)
		(fp_line
			(start 0.12065 0.3048)
			(end 0.67945 0.3048)
			(stroke
				(width 0.1)
				(type default)
			)
			(layer "B.Fab")
		)
		(fp_line
			(start 0.12065 0.2794)
			(end 0.12065 0.3048)
			(stroke
				(width 0.1)
				(type default)
			)
			(layer "B.Fab")
		)
		(fp_line
			(start 0.12065 -0.2794)
			(end -0.12065 -0.2794)
			(stroke
				(width 0.1)
				(type default)
			)
			(layer "B.Fab")
		)
		(fp_line
			(start 0.12065 -0.305054)
			(end 0.12065 -0.2794)
			(stroke
				(width 0.1)
				(type default)
			)
			(layer "B.Fab")
		)
		(fp_line
			(start -0.120396 0.3048)
			(end -0.120396 0.2794)
			(stroke
				(width 0.1)
				(type default)
			)
			(layer "B.Fab")
		)
		(fp_line
			(start -0.120396 0.2794)
			(end 0.12065 0.2794)
			(stroke
				(width 0.1)
				(type default)
			)
			(layer "B.Fab")
		)
		(fp_line
			(start -0.12065 -0.2794)
			(end -0.12065 -0.3048)
			(stroke
				(width 0.1)
				(type default)
			)
			(layer "B.Fab")
		)
		(fp_line
			(start -0.12065 -0.3048)
			(end -0.67945 -0.3048)
			(stroke
				(width 0.1)
				(type default)
			)
			(layer "B.Fab")
		)
		(fp_line
			(start -0.67945 0.3048)
			(end -0.120396 0.3048)
			(stroke
				(width 0.1)
				(type default)
			)
			(layer "B.Fab")
		)
		(fp_line
			(start -0.67945 -0.3048)
			(end -0.67945 0.3048)
			(stroke
				(width 0.1)
				(type default)
			)
			(layer "B.Fab")
		)
		(pad "1" smd circle
			(at 0.40005 0)
			(size 0 0)
			(layers "B.Cu" "B.Mask" "B.Paste")
			(net "PD_CHF_CPU0_DIMM_SAA")
		)
		(pad "2" smd circle
			(at -0.40005 0)
			(size 0 0)
			(layers "B.Cu" "B.Mask" "B.Paste")
			(net "GND")
		)
	)
	(footprint ""
		(layer "B.Cu")
		(at 190.404496 -195.8594 180)
		(property "Reference" "R1709"
			(at 0 0 0)
			(layer "B.SilkS")
			(hide yes)
			(effects
				(font
					(size 1.27 1.27)
				)
				(justify mirror)
			)
		)
		(property "Value" ""
			(at 0 0 0)
			(layer "B.Fab")
			(effects
				(font
					(size 1.27 1.27)
				)
				(justify mirror)
			)
		)
		(duplicate_pad_numbers_are_jumpers no)
		(fp_line
			(start 0.7874 0.4064)
			(end 0.7874 -0.4064)
			(stroke
				(width 0.1524)
				(type default)
			)
			(layer "B.SilkS")
		)
		(fp_line
			(start 0.7874 -0.4064)
			(end -0.7874 -0.4064)
			(stroke
				(width 0.1524)
				(type default)
			)
			(layer "B.SilkS")
		)
		(fp_line
			(start -0.7874 0.4064)
			(end 0.7874 0.4064)
			(stroke
				(width 0.1524)
				(type default)
			)
			(layer "B.SilkS")
		)
		(fp_line
			(start -0.7874 -0.4064)
			(end -0.7874 0.4064)
			(stroke
				(width 0.1524)
				(type default)
			)
			(layer "B.SilkS")
		)
		(fp_line
			(start 0.67945 0.3048)
			(end 0.67945 -0.305054)
			(stroke
				(width 0.1)
				(type default)
			)
			(layer "B.Fab")
		)
		(fp_line
			(start 0.67945 -0.305054)
			(end 0.12065 -0.305054)
			(stroke
				(width 0.1)
				(type default)
			)
			(layer "B.Fab")
		)
		(fp_line
			(start 0.12065 0.3048)
			(end 0.67945 0.3048)
			(stroke
				(width 0.1)
				(type default)
			)
			(layer "B.Fab")
		)
		(fp_line
			(start 0.12065 0.2794)
			(end 0.12065 0.3048)
			(stroke
				(width 0.1)
				(type default)
			)
			(layer "B.Fab")
		)
		(fp_line
			(start 0.12065 -0.2794)
			(end -0.12065 -0.2794)
			(stroke
				(width 0.1)
				(type default)
			)
			(layer "B.Fab")
		)
		(fp_line
			(start 0.12065 -0.305054)
			(end 0.12065 -0.2794)
			(stroke
				(width 0.1)
				(type default)
			)
			(layer "B.Fab")
		)
		(fp_line
			(start -0.120396 0.3048)
			(end -0.120396 0.2794)
			(stroke
				(width 0.1)
				(type default)
			)
			(layer "B.Fab")
		)
		(fp_line
			(start -0.120396 0.2794)
			(end 0.12065 0.2794)
			(stroke
				(width 0.1)
				(type default)
			)
			(layer "B.Fab")
		)
		(fp_line
			(start -0.12065 -0.2794)
			(end -0.12065 -0.3048)
			(stroke
				(width 0.1)
				(type default)
			)
			(layer "B.Fab")
		)
		(fp_line
			(start -0.12065 -0.3048)
			(end -0.67945 -0.3048)
			(stroke
				(width 0.1)
				(type default)
			)
			(layer "B.Fab")
		)
		(fp_line
			(start -0.67945 0.3048)
			(end -0.120396 0.3048)
			(stroke
				(width 0.1)
				(type default)
			)
			(layer "B.Fab")
		)
		(fp_line
			(start -0.67945 -0.3048)
			(end -0.67945 0.3048)
			(stroke
				(width 0.1)
				(type default)
			)
			(layer "B.Fab")
		)
		(pad "1" smd circle
			(at 0.40005 0)
			(size 0 0)
			(layers "B.Cu" "B.Mask" "B.Paste")
			(net "I3C_SPD_DDRGL_CPU1_SDA")
		)
		(pad "2" smd circle
			(at -0.40005 0)
			(size 0 0)
			(layers "B.Cu" "B.Mask" "B.Paste")
			(net "I3C_SPD_DDRJ_CPU1_SDA")
		)
	)
	(footprint ""
		(layer "B.Cu")
		(at 136.040114 -33.834578)
		(property "Reference" "C6038"
			(at 0 0 0)
			(layer "B.SilkS")
			(hide yes)
			(effects
				(font
					(size 1.27 1.27)
				)
				(justify mirror)
			)
		)
		(property "Value" ""
			(at 0 0 0)
			(layer "B.Fab")
			(effects
				(font
					(size 1.27 1.27)
				)
				(justify mirror)
			)
		)
		(duplicate_pad_numbers_are_jumpers no)
		(fp_line
			(start -0.7874 -0.4064)
			(end -0.7874 0.4064)
			(stroke
				(width 0.1524)
				(type default)
			)
			(layer "B.SilkS")
		)
		(fp_line
			(start -0.7874 0.4064)
			(end 0.7874 0.4064)
			(stroke
				(width 0.1524)
				(type default)
			)
			(layer "B.SilkS")
		)
		(fp_line
			(start 0.7874 -0.4064)
			(end -0.7874 -0.4064)
			(stroke
				(width 0.1524)
				(type default)
			)
			(layer "B.SilkS")
		)
		(fp_line
			(start 0.7874 0.4064)
			(end 0.7874 -0.4064)
			(stroke
				(width 0.1524)
				(type default)
			)
			(layer "B.SilkS")
		)
		(fp_line
			(start -0.67945 -0.3048)
			(end -0.67945 0.3048)
			(stroke
				(width 0.1)
				(type default)
			)
			(layer "B.Fab")
		)
		(fp_line
			(start -0.67945 0.3048)
			(end -0.120396 0.3048)
			(stroke
				(width 0.1)
				(type default)
			)
			(layer "B.Fab")
		)
		(fp_line
			(start -0.12065 -0.3048)
			(end -0.67945 -0.3048)
			(stroke
				(width 0.1)
				(type default)
			)
			(layer "B.Fab")
		)
		(fp_line
			(start -0.12065 -0.2794)
			(end -0.12065 -0.3048)
			(stroke
				(width 0.1)
				(type default)
			)
			(layer "B.Fab")
		)
		(fp_line
			(start -0.120396 0.2794)
			(end 0.12065 0.2794)
			(stroke
				(width 0.1)
				(type default)
			)
			(layer "B.Fab")
		)
		(fp_line
			(start -0.120396 0.3048)
			(end -0.120396 0.2794)
			(stroke
				(width 0.1)
				(type default)
			)
			(layer "B.Fab")
		)
		(fp_line
			(start 0.12065 -0.305054)
			(end 0.12065 -0.2794)
			(stroke
				(width 0.1)
				(type default)
			)
			(layer "B.Fab")
		)
		(fp_line
			(start 0.12065 -0.2794)
			(end -0.12065 -0.2794)
			(stroke
				(width 0.1)
				(type default)
			)
			(layer "B.Fab")
		)
		(fp_line
			(start 0.12065 0.2794)
			(end 0.12065 0.3048)
			(stroke
				(width 0.1)
				(type default)
			)
			(layer "B.Fab")
		)
		(fp_line
			(start 0.12065 0.3048)
			(end 0.67945 0.3048)
			(stroke
				(width 0.1)
				(type default)
			)
			(layer "B.Fab")
		)
		(fp_line
			(start 0.67945 -0.305054)
			(end 0.12065 -0.305054)
			(stroke
				(width 0.1)
				(type default)
			)
			(layer "B.Fab")
		)
		(fp_line
			(start 0.67945 0.3048)
			(end 0.67945 -0.305054)
			(stroke
				(width 0.1)
				(type default)
			)
			(layer "B.Fab")
		)
		(pad "1" smd circle
			(at 0.40005 0 180)
			(size 0 0)
			(layers "B.Cu" "B.Mask" "B.Paste")
			(net "P1V2_CPU0_USB_DVDD12")
		)
		(pad "2" smd circle
			(at -0.40005 0 180)
			(size 0 0)
			(layers "B.Cu" "B.Mask" "B.Paste")
			(net "GND")
		)
	)
)
